# BASEBOARD_FAB2 (Tioga Pass) — schematic netlist excerpt (pin names and nets, part order shuffled) for the footprints in the layout excerpt that follows; sources: Cadence DE-HDL packaged netlist, KiCad conversion of Wiwynn_Tioga_Pass_MB.brd

C7C1  CAP  0.22UF 16V 10% X7R  pkg 0402  page 129 : A = DMI_CPU0_PCH_TX_DN<1> ; B = DMI_CPU0_PCH_TX_C_DN<1>
C1A4  CAP  10UF 16V 10% X7R  pkg 0805  page 197 : A = P12V_NVDIMM_KLM ; B = GND
CF20  SC22P50V2JN-4GP  5%  pkg SMD-BCG  page 223 : \1\ = VR_PVDDQ_GHJ_AIREF2 ; \2\ = ISENSE_PVDDQ_GHJ_PH2_IMON

(kicad_pcb
	(version 20260206)
	(generator "pcbnew")
	(generator_version "10.0")
	(general
		(thickness 1.6)
		(legacy_teardrops no)
	)
	(paper "A4")
	(title_block
		(title "Wiwynn_Tioga_Pass_MB.brd")
		(comment 1 "Tioga Pass / footprints 1831-1833 of 4770")
	)
	(layers
		(0 "F.Cu" signal "TOP")
		(4 "In1.Cu" signal "L2GND")
		(6 "In2.Cu" signal "L3")
		(8 "In3.Cu" signal "L4GND")
		(10 "In4.Cu" signal "L5")
		(12 "In5.Cu" signal "L6GND")
		(14 "In6.Cu" signal "L7VCC")
		(16 "In7.Cu" signal "L8VCC")
		(18 "In8.Cu" signal "L9GND")
		(20 "In9.Cu" signal "L10")
		(22 "In10.Cu" signal "L11GND")
		(24 "In11.Cu" signal "L12")
		(26 "In12.Cu" signal "L13GND")
		(2 "B.Cu" signal "BOTTOM")
		(9 "F.Adhes" user "F.Adhesive")
		(11 "B.Adhes" user "B.Adhesive")
		(13 "F.Paste" user "Package Geometry/Pastemask Top")
		(15 "B.Paste" user "Package Geometry/Pastemask Bottom")
		(5 "F.SilkS" user "Ref Des/Silkscreen Top")
		(7 "B.SilkS" user "Ref Des/Silkscreen Bottom")
		(1 "F.Mask" user "Board Geometry/Soldermask Top")
		(3 "B.Mask" user "Board Geometry/Soldermask Bottom")
		(17 "Dwgs.User" user "User.Drawings")
		(19 "Cmts.User" user "User.Comments")
		(21 "Eco1.User" user "User.Eco1")
		(23 "Eco2.User" user "User.Eco2")
		(25 "Edge.Cuts" user "Board Geometry/Outline")
		(27 "Margin" user)
		(31 "F.CrtYd" user "Package Geometry/Place Bound Top")
		(29 "B.CrtYd" user "Package Geometry/Place Bound Bottom")
		(35 "F.Fab" user "Ref Des/Assembly Top")
		(33 "B.Fab" user "Ref Des/Assembly Bottom")
	)
	(footprint ""
		(layer "F.Cu")
		(at 28.380182 -149.7838 -90)
		(property "Reference" "C1A4"
			(at 0 0 270)
			(layer "F.SilkS")
			(hide yes)
			(effects
				(font
					(size 1.27 1.27)
				)
			)
		)
		(property "Value" ""
			(at 0 0 270)
			(layer "F.Fab")
			(effects
				(font
					(size 1.27 1.27)
				)
			)
		)
		(duplicate_pad_numbers_are_jumpers no)
		(fp_poly
			(pts
				(xy -0.7239 -0.2159) (xy 0.7239 -0.2159) (xy 0.7239 1.9939) (xy -0.7239 1.9939)
			)
			(stroke
				(width 0)
				(type default)
			)
			(fill no)
			(layer "F.CrtYd")
		)
		(fp_line
			(start -0.7239 1.9939)
			(end 0.7239 1.9939)
			(stroke
				(width 0.1)
				(type default)
			)
			(layer "F.Fab")
		)
		(fp_line
			(start 0.7239 1.9939)
			(end 0.7239 -0.2159)
			(stroke
				(width 0.1)
				(type default)
			)
			(layer "F.Fab")
		)
		(fp_line
			(start -0.7239 -0.2159)
			(end -0.7239 1.9939)
			(stroke
				(width 0.1)
				(type default)
			)
			(layer "F.Fab")
		)
		(fp_line
			(start 0.7239 -0.2159)
			(end -0.7239 -0.2159)
			(stroke
				(width 0.1)
				(type default)
			)
			(layer "F.Fab")
		)
		(pad "1" smd rect
			(at 0 0 270)
			(size 1.27 1.016)
			(layers "F.Cu" "F.Mask" "F.Paste")
			(net "P12V_NVDIMM_KLM")
		)
		(pad "2" smd rect
			(at 0 1.778 270)
			(size 1.27 1.016)
			(layers "F.Cu" "F.Mask" "F.Paste")
			(net "GND")
		)
		(zone
			(layer "F.Cu")
			(hatch none 0.5)
			(connect_pads
				(clearance 0)
			)
			(min_thickness 0.25)
			(keepout
				(tracks not_allowed)
				(vias allowed)
				(pads allowed)
				(copperpour not_allowed)
				(footprints allowed)
			)
			(placement
				(enabled no)
				(sheetname "")
			)
			(fill
				(thermal_gap 0.5)
				(thermal_bridge_width 0.5)
				(island_removal_mode 0)
			)
			(polygon
				(pts
					(xy 27.872182 -150.4188) (xy 27.872182 -149.1488) (xy 27.110182 -149.1488) (xy 27.110182 -150.4188)
				)
			)
		)
	)
	(footprint ""
		(layer "F.Cu")
		(at 5.909056 2.91846 90)
		(property "Reference" "CF20"
			(at 0 0 90)
			(layer "F.SilkS")
			(hide yes)
			(effects
				(font
					(size 1.27 1.27)
				)
			)
		)
		(property "Value" "*"
			(at 1.1811 -2.8194 90)
			(unlocked yes)
			(layer "F.Fab")
			(hide yes)
			(effects
				(font
					(size 1.27 1.016)
					(thickness 0.1524)
				)
			)
		)
		(property "Device Type" "SC22P50V2JN-4GP_SMD-BCG-SC22P5A"
			(at 1.1811 -4.3434 90)
			(unlocked yes)
			(layer "F.Fab")
			(hide yes)
			(effects
				(font
					(size 1.27 1.016)
					(thickness 0.1524)
				)
			)
		)
		(duplicate_pad_numbers_are_jumpers no)
		(fp_rect
			(start -0.4318 0.9525)
			(end 0.4318 -0.9525)
			(stroke
				(width 0)
				(type default)
			)
			(fill no)
			(layer "F.CrtYd")
		)
		(fp_rect
			(start -0.4318 0.9525)
			(end 0.4318 -0.9525)
			(stroke
				(width 0)
				(type default)
			)
			(fill no)
			(layer "F.Fab")
		)
		(pad "1" smd custom
			(at 0 -0.4445 90)
			(size 0.1524 0.1524)
			(layers "F.Cu" "F.Mask" "F.Paste")
			(net "VR_PVDDQ_GHJ_AIREF2")
			(options
				(clearance outline)
				(anchor circle)
			)
			(primitives
				(gr_poly
					(pts
						(arc
							(start 0.3048 -0.2032)
							(mid 0.275042 -0.275042)
							(end 0.2032 -0.3048)
						)
						(arc
							(start -0.2032 -0.3048)
							(mid -0.275042 -0.275042)
							(end -0.3048 -0.2032)
						)
						(arc
							(start -0.3048 0.2032)
							(mid -0.275042 0.275042)
							(end -0.2032 0.3048)
						)
						(arc
							(start 0.2032 0.3048)
							(mid 0.275042 0.275042)
							(end 0.3048 0.2032)
						)
					)
					(width 0)
					(fill yes)
				)
			)
		)
		(pad "2" smd custom
			(at 0 0.4445 90)
			(size 0.1524 0.1524)
			(layers "F.Cu" "F.Mask" "F.Paste")
			(net "ISENSE_PVDDQ_GHJ_PH2_IMON")
			(options
				(clearance outline)
				(anchor circle)
			)
			(primitives
				(gr_poly
					(pts
						(arc
							(start 0.3048 -0.2032)
							(mid 0.275042 -0.275042)
							(end 0.2032 -0.3048)
						)
						(arc
							(start -0.2032 -0.3048)
							(mid -0.275042 -0.275042)
							(end -0.3048 -0.2032)
						)
						(arc
							(start -0.3048 0.2032)
							(mid -0.275042 0.275042)
							(end -0.2032 0.3048)
						)
						(arc
							(start 0.2032 0.3048)
							(mid 0.275042 0.275042)
							(end 0.3048 0.2032)
						)
					)
					(width 0)
					(fill yes)
				)
			)
		)
	)
	(footprint ""
		(layer "F.Cu")
		(at 364.617 -110.998 90)
		(property "Reference" "C7C1"
			(at 0 0 90)
			(layer "F.SilkS")
			(hide yes)
			(effects
				(font
					(size 1.27 1.27)
				)
			)
		)
		(property "Value" ""
			(at 0 0 90)
			(layer "F.Fab")
			(effects
				(font
					(size 1.27 1.27)
				)
			)
		)
		(duplicate_pad_numbers_are_jumpers no)
		(fp_poly
			(pts
				(xy 0.3048 -0.1016) (xy 0.3048 0.9906) (xy -0.3048 0.9906) (xy -0.3048 -0.1016)
			)
			(stroke
				(width 0)
				(type default)
			)
			(fill no)
			(layer "F.CrtYd")
		)
		(fp_line
			(start 0.3048 -0.1016)
			(end -0.3048 -0.1016)
			(stroke
				(width 0.1)
				(type default)
			)
			(layer "F.Fab")
		)
		(fp_line
			(start -0.3048 -0.1016)
			(end -0.3048 0.9906)
			(stroke
				(width 0.1)
				(type default)
			)
			(layer "F.Fab")
		)
		(fp_line
			(start 0.3048 0.9906)
			(end 0.3048 -0.1016)
			(stroke
				(width 0.1)
				(type default)
			)
			(layer "F.Fab")
		)
		(fp_line
			(start -0.3048 0.9906)
			(end 0.3048 0.9906)
			(stroke
				(width 0.1)
				(type default)
			)
			(layer "F.Fab")
		)
		(pad "1" smd rect
			(at 0 0 90)
			(size 0.508 0.508)
			(layers "F.Cu" "F.Mask" "F.Paste")
			(net "DMI_CPU0_PCH_TX_DN<1>")
		)
		(pad "2" smd rect
			(at 0 0.889 90)
			(size 0.508 0.508)
			(layers "F.Cu" "F.Mask" "F.Paste")
			(net "DMI_CPU0_PCH_TX_C_DN<1>")
		)
		(zone
			(layer "F.Cu")
			(hatch none 0.5)
			(connect_pads
				(clearance 0)
			)
			(min_thickness 0.25)
			(keepout
				(tracks allowed)
				(vias not_allowed)
				(pads allowed)
				(copperpour not_allowed)
				(footprints allowed)
			)
			(placement
				(enabled no)
				(sheetname "")
			)
			(fill
				(thermal_gap 0.5)
				(thermal_bridge_width 0.5)
				(island_removal_mode 0)
			)
			(polygon
				(pts
					(xy 364.871 -110.744) (xy 364.871 -111.252) (xy 365.252 -111.252) (xy 365.252 -110.744)
				)
			)
		)
		(zone
			(layer "F.Cu")
			(hatch none 0.5)
			(connect_pads
				(clearance 0)
			)
			(min_thickness 0.25)
			(keepout
				(tracks not_allowed)
				(vias allowed)
				(pads allowed)
				(copperpour not_allowed)
				(footprints allowed)
			)
			(placement
				(enabled no)
				(sheetname "")
			)
			(fill
				(thermal_gap 0.5)
				(thermal_bridge_width 0.5)
				(island_removal_mode 0)
			)
			(polygon
				(pts
					(xy 365.252 -110.744) (xy 365.252 -111.252) (xy 364.871 -111.252) (xy 364.871 -110.744)
				)
			)
		)
	)
)
